# T6G (Grand Teton) — schematic netlist excerpt (pin names and nets, part order shuffled) for the footprints in the layout excerpt that follows; sources: Cadence DE-HDL packaged netlist, KiCad conversion of 04192023_DAF0TMB3IC0_F0TG_MB_C_brd_V02_OCP.brd

J15  SCONN288_DDR506112002KQ  IO  pkg DDR288S_1-1VXC  page 87
  VIN_BULK0  = P12V_MEM_CPU0
  RFU0  = NC
  VIN_MGMT  = P3V3_AUX
  HSCL  = I3C_SPD_DDRB_CPU0_SCL
  HSDA  = I3C_SPD_DDRB_CPU0_SDA
  VSS0  = GND
  DQ0_A  = M_B_CPU0_SA_DQ<0>
  VSS1  = GND
  DQ1_A  = M_B_CPU0_SA_DQ<1>
  VSS2  = GND
  DQS0_A_T  = M_B_CPU0_SA_DQS_DP<0>
  DQS0_A_C  = M_B_CPU0_SA_DQS_DN<0>
  VSS3  = GND
  DQ4_A  = M_B_CPU0_SA_DQ<4>
  VSS4  = GND
  DQ5_A  = M_B_CPU0_SA_DQ<5>
  VSS5  = GND
  DQ8_A  = M_B_CPU0_SA_DQ<8>
  VSS6  = GND
  DQ9_A  = M_B_CPU0_SA_DQ<9>
  VSS7  = GND
  DQS1_A_T  = M_B_CPU0_SA_DQS_DP<1>
  DQS1_A_C  = M_B_CPU0_SA_DQS_DN<1>
  VSS8  = GND
  DQ12_A  = M_B_CPU0_SA_DQ<12>
  VSS9  = GND
  DQ13_A  = M_B_CPU0_SA_DQ<13>
  VSS10  = GND
  DQ16_A  = M_B_CPU0_SA_DQ<16>
  VSS11  = GND
  DQ17_A  = M_B_CPU0_SA_DQ<17>
  VSS12  = GND
  DQS2_A_T  = M_B_CPU0_SA_DQS_DP<2>
  DQS2_A_C  = M_B_CPU0_SA_DQS_DN<2>
  VSS13  = GND
  DQ20_A  = M_B_CPU0_SA_DQ<20>
  VSS14  = GND
  DQ21_A  = M_B_CPU0_SA_DQ<21>
  VSS15  = GND
  DQ24_A  = M_B_CPU0_SA_DQ<24>
  VSS16  = GND
  DQ25_A  = M_B_CPU0_SA_DQ<25>
  VSS17  = GND
  DQS3_A_T  = M_B_CPU0_SA_DQS_DP<3>
  DQS3_A_C  = M_B_CPU0_SA_DQS_DN<3>
  VSS18  = GND
  DQ28_A  = M_B_CPU0_SA_DQ<28>
  VSS19  = GND
  DQ29_A  = M_B_CPU0_SA_DQ<29>
  VSS20  = GND
  CB0_A  = M_B_CPU0_SA_CB<0>
  VSS21  = GND
  CB1_A  = M_B_CPU0_SA_CB<1>
  VSS22  = GND
  DQS4_A_T  = M_B_CPU0_SA_DQS_DP<4>
  DQS4_A_C  = M_B_CPU0_SA_DQS_DN<4>
  VSS23  = GND
  CB4_A  = M_B_CPU0_SA_CB<4>
  VSS24  = GND
  CB5_A  = M_B_CPU0_SA_CB<5>
  VSS25  = GND
  ALERT_N  = M_B_CPU0_ALERT_N
  VSS26  = GND
  CS0_A_N  = M_B_CPU0_SA_CS_N<0>
  VSS27  = GND
  CA0_A  = M_B_CPU0_SA_CA<0>
  VSS28  = GND
  CA2_A  = M_B_CPU0_SA_CA<2>
  VSS29  = GND
  CA4_A  = M_B_CPU0_SA_CA<4>
  VSS30  = GND
  CA6_A  = M_B_CPU0_SA_CA<6>
  VSS31  = GND
  PAR_A  = M_B_CPU0_SA_PAR
  VSS32  = GND
  CA0_B  = M_B_CPU0_SB_CA<0>
  VSS33  = GND
  CA2_B  = M_B_CPU0_SB_CA<2>
  VSS34  = GND
  CA4_B  = M_B_CPU0_SB_CA<4>
  VSS35  = GND
  CA6_B  = M_B_CPU0_SB_CA<6>
  VSS36  = GND
  CS0_B_N  = M_B_CPU0_SB_CS_N<0>
  VSS37  = GND
  \lbd||rsp_a_n\  = M_B_CPU0_SA_RSP<0>
  \lbs||rsp_b_n\  = M_B_CPU0_SB_RSP<0>
  VSS38  = GND
  CB4_B  = M_B_CPU0_SB_CB<4>
  VSS39  = GND
  CB5_B  = M_B_CPU0_SB_CB<5>
  VSS40  = GND
  \dqs9_b_t||tdqs9_b_t||dbi4_b_n\  = M_B_CPU0_SB_DQS_DP<9>
  \dqs9_b_c||tdqs9_b_c\  = M_B_CPU0_SB_DQS_DN<9>
  VSS41  = GND
  CB0_B  = M_B_CPU0_SB_CB<0>
  VSS42  = GND
  CB1_B  = M_B_CPU0_SB_CB<1>
  VSS43  = GND
  DQ0_B  = M_B_CPU0_SB_DQ<0>
  VSS44  = GND
  DQ1_B  = M_B_CPU0_SB_DQ<1>
  VSS45  = GND
  DQS0_B_T  = M_B_CPU0_SB_DQS_DP<0>
  DQS0_B_C  = M_B_CPU0_SB_DQS_DN<0>
  VSS46  = GND
  DQ4_B  = M_B_CPU0_SB_DQ<4>
  VSS47  = GND
  DQ5_B  = M_B_CPU0_SB_DQ<5>
  VSS48  = GND
  DQ8_B  = M_B_CPU0_SB_DQ<8>
  VSS49  = GND
  DQ9_B  = M_B_CPU0_SB_DQ<9>
  VSS50  = GND
  DQS1_B_T  = M_B_CPU0_SB_DQS_DP<1>
  DQS1_B_C  = M_B_CPU0_SB_DQS_DN<1>
  VSS51  = GND
  DQ12_B  = M_B_CPU0_SB_DQ<12>
  VSS52  = GND
  DQ13_B  = M_B_CPU0_SB_DQ<13>
  VSS53  = GND
  DQ16_B  = M_B_CPU0_SB_DQ<16>
  VSS54  = GND
  DQ17_B  = M_B_CPU0_SB_DQ<17>
  VSS55  = GND
  DQS2_B_T  = M_B_CPU0_SB_DQS_DP<2>
  DQS2_B_C  = M_B_CPU0_SB_DQS_DN<2>
  VSS56  = GND
  DQ20_B  = M_B_CPU0_SB_DQ<20>
  VSS57  = GND
  DQ21_B  = M_B_CPU0_SB_DQ<21>
  VSS58  = GND
  DQ24_B  = M_B_CPU0_SB_DQ<24>
  VSS59  = GND
  DQ25_B  = M_B_CPU0_SB_DQ<25>
  VSS60  = GND
  DQS3_B_T  = M_B_CPU0_SB_DQS_DP<3>
  DQS3_B_C  = M_B_CPU0_SB_DQS_DN<3>
  VSS61  = GND
  DQ28_B  = M_B_CPU0_SB_DQ<28>
  VSS62  = GND
  DQ29_B  = M_B_CPU0_SB_DQ<29>
  VSS63  = GND
  RFU1  = NC
  VIN_BULK1  = P12V_MEM_CPU0
  VIN_BULK2  = P12V_MEM_CPU0
  \pwr_good||fail_n\  = PWRGD_CHB_CPU0_DIMM
  HAS  = PD_CHB_CPU0_DIMM_SAA
  RFU2  = NC
  RFU3  = NC
  VSS64  = GND
  DQ2_A  = M_B_CPU0_SA_DQ<2>
  VSS65  = GND
  DQ3_A  = M_B_CPU0_SA_DQ<3>
  VSS66  = GND
  \dqs5_a_c||tdqs5_a_c||dqs5_a_t||tdqs5_a_t\  = M_B_CPU0_SA_DQS_DN<5>
  \dqs5_a_t||tdqs5_a_t\  = M_B_CPU0_SA_DQS_DP<5>
  VSS67  = GND
  DQ6_A  = M_B_CPU0_SA_DQ<6>
  VSS68  = GND
  DQ7_A  = M_B_CPU0_SA_DQ<7>
  VSS69  = GND
  DQ10_A  = M_B_CPU0_SA_DQ<10>
  VSS70  = GND
  DQ11_A  = M_B_CPU0_SA_DQ<11>
  VSS71  = GND
  \dqs6_a_c||tdqs6_a_c||dqs6_a_t||tdqs6_a_t\  = M_B_CPU0_SA_DQS_DN<6>
  \dqs6_a_t||tdqs6_a_t\  = M_B_CPU0_SA_DQS_DP<6>
  VSS72  = GND
  DQ14_A  = M_B_CPU0_SA_DQ<14>
  VSS73  = GND
  DQ15_A  = M_B_CPU0_SA_DQ<15>
  VSS74  = GND
  DQ18_A  = M_B_CPU0_SA_DQ<18>
  VSS75  = GND
  DQ19_A  = M_B_CPU0_SA_DQ<19>
  VSS76  = GND
  \dqs7_a_c||tdqs7_a_c\  = M_B_CPU0_SA_DQS_DN<7>
  \dqs7_a_t||tdqs7_a_t\  = M_B_CPU0_SA_DQS_DP<7>
  VSS77  = GND
  DQ22_A  = M_B_CPU0_SA_DQ<22>
  VSS78  = GND
  DQ23_A  = M_B_CPU0_SA_DQ<23>
  VSS79  = GND
  DQ26_A  = M_B_CPU0_SA_DQ<26>
  VSS80  = GND
  DQ27_A  = M_B_CPU0_SA_DQ<27>
  VSS81  = GND
  \dqs8_a_c||tdqs8_a_c\  = M_B_CPU0_SA_DQS_DN<8>
  \dqs8_a_t||tdqs8_a_t\  = M_B_CPU0_SA_DQS_DP<8>
  VSS82  = GND
  DQ30_A  = M_B_CPU0_SA_DQ<30>
  VSS83  = GND
  DQ31_A  = M_B_CPU0_SA_DQ<31>
  VSS84  = GND
  CB2_A  = M_B_CPU0_SA_CB<2>
  VSS85  = GND
  CB3_A  = M_B_CPU0_SA_CB<3>
  VSS86  = GND
  \dqs9_a_c||tdqs9_a_c\  = M_B_CPU0_SA_DQS_DN<9>
  \dqs9_a_t||tdqs9_a_t\  = M_B_CPU0_SA_DQS_DP<9>
  VSS87  = GND
  CB6_A  = M_B_CPU0_SA_CB<6>
  VSS88  = GND
  CB7_A  = M_B_CPU0_SA_CB<7>
  VSS89  = GND
  RESET_N  = M_B_CPU0_RESET_N
  VSS90  = GND
  CS1_A_N  = M_B_CPU0_SA_CS_N<1>
  VSS91  = GND
  CA1_A  = M_B_CPU0_SA_CA<1>
  VSS92  = GND
  CA3_A  = M_B_CPU0_SA_CA<3>
  VSS93  = GND
  CA5_A  = M_B_CPU0_SA_CA<5>
  VSS94  = GND
  CK_T  = M_B_CPU0_CLK_DP<0>
  CK_C  = M_B_CPU0_CLK_DN<0>
  VSS95  = GND
  RFU4  = NC
  CA1_B  = M_B_CPU0_SB_CA<1>
  VSS96  = GND
  CA3_B  = M_B_CPU0_SB_CA<3>
  VSS97  = GND
  CA5_B  = M_B_CPU0_SB_CA<5>
  VSS98  = GND
  PAR_B  = M_B_CPU0_SB_PAR
  VSS99  = GND
  CS1_B_N  = M_B_CPU0_SB_CS_N<1>
  VSS100  = GND
  RFU5  = NC
  RFU6  = NC
  VSS101  = GND
  CB6_B  = M_B_CPU0_SB_CB<6>
  VSS102  = GND
  CB7_B  = M_B_CPU0_SB_CB<7>
  VSS103  = GND
  DQS4_B_C  = M_B_CPU0_SB_DQS_DN<4>
  DQS4_B_T  = M_B_CPU0_SB_DQS_DP<4>
  VSS104  = GND
  CB2_B  = M_B_CPU0_SB_CB<2>
  VSS105  = GND
  CB3_B  = M_B_CPU0_SB_CB<3>
  VSS106  = GND
  DQ2_B  = M_B_CPU0_SB_DQ<2>
  VSS107  = GND
  DQ3_B  = M_B_CPU0_SB_DQ<3>
  VSS108  = GND
  \dqs5_b_c||tdqs5_b_c\  = M_B_CPU0_SB_DQS_DN<5>
  \dqs5_b_t||tdqs5_b_t\  = M_B_CPU0_SB_DQS_DP<5>
  VSS109  = GND
  DQ6_B  = M_B_CPU0_SB_DQ<6>
  VSS110  = GND
  DQ7_B  = M_B_CPU0_SB_DQ<7>
  VSS111  = GND
  DQ10_B  = M_B_CPU0_SB_DQ<10>
  VSS112  = GND
  DQ11_B  = M_B_CPU0_SB_DQ<11>
  VSS113  = GND
  \dqs6_b_c||tdqs6_b_c\  = M_B_CPU0_SB_DQS_DN<6>
  \dqs6_b_t||tdqs6_b_t\  = M_B_CPU0_SB_DQS_DP<6>
  VSS114  = GND
  DQ14_B  = M_B_CPU0_SB_DQ<14>
  VSS115  = GND
  DQ15_B  = M_B_CPU0_SB_DQ<15>
  VSS116  = GND
  DQ18_B  = M_B_CPU0_SB_DQ<18>
  VSS117  = GND
  DQ19_B  = M_B_CPU0_SB_DQ<19>
  VSS118  = GND
  \dqs7_b_c||tdqs7_b_c\  = M_B_CPU0_SB_DQS_DN<7>
  \dqs7_b_t||tdqs7_b_t\  = M_B_CPU0_SB_DQS_DP<7>
  VSS119  = GND
  DQ22_B  = M_B_CPU0_SB_DQ<22>
  VSS120  = GND
  DQ23_B  = M_B_CPU0_SB_DQ<23>
  VSS121  = GND
  DQ26_B  = M_B_CPU0_SB_DQ<26>
  VSS122  = GND
  DQ27_B  = M_B_CPU0_SB_DQ<27>
  VSS123  = GND
  \dqs8_b_c||tdqs8_b_c\  = M_B_CPU0_SB_DQS_DN<8>
  \dqs8_b_t||tdqs8_b_t\  = M_B_CPU0_SB_DQS_DP<8>
  VSS124  = GND
  DQ30_B  = M_B_CPU0_SB_DQ<30>
  VSS125  = GND
  DQ31_B  = M_B_CPU0_SB_DQ<31>
  VSS126  = GND
  G1  = GND
  G2  = GND
  G3  = GND

(kicad_pcb
	(version 20260206)
	(generator "pcbnew")
	(generator_version "10.0")
	(general
		(thickness 1.6)
		(legacy_teardrops no)
	)
	(paper "A4")
	(title_block
		(title "04192023_DAF0TMB3IC0_F0TG_MB_C_brd_V02_OCP.brd")
		(comment 1 "Grand Teton / footprint 1120 of 8354 (J15), pads 139-184 of 291")
	)
	(layers
		(0 "F.Cu" signal "TOP")
		(4 "In1.Cu" signal "GND")
		(6 "In2.Cu" signal "IN1")
		(8 "In3.Cu" signal "GND1")
		(10 "In4.Cu" signal "IN2")
		(12 "In5.Cu" signal "GND2")
		(14 "In6.Cu" signal "IN3")
		(16 "In7.Cu" signal "GND3")
		(18 "In8.Cu" signal "VCC")
		(20 "In9.Cu" signal "VCC1")
		(22 "In10.Cu" signal "GND4")
		(24 "In11.Cu" signal "IN4")
		(26 "In12.Cu" signal "GND5")
		(28 "In13.Cu" signal "IN5")
		(30 "In14.Cu" signal "GND6")
		(32 "In15.Cu" signal "IN6")
		(34 "In16.Cu" signal "GND7")
		(2 "B.Cu" signal "BOTTOM")
		(9 "F.Adhes" user "F.Adhesive")
		(11 "B.Adhes" user "B.Adhesive")
		(13 "F.Paste" user "Package Geometry/Pastemask Top")
		(15 "B.Paste" user "Package Geometry/Pastemask Bottom")
		(5 "F.SilkS" user "Ref Des/Silkscreen Top")
		(7 "B.SilkS" user "Ref Des/Silkscreen Bottom")
		(1 "F.Mask" user "Board Geometry/Soldermask Top")
		(3 "B.Mask" user "Board Geometry/Soldermask Bottom")
		(17 "Dwgs.User" user "User.Drawings")
		(19 "Cmts.User" user "User.Comments")
		(21 "Eco1.User" user "User.Eco1")
		(23 "Eco2.User" user "User.Eco2")
		(25 "Edge.Cuts" user "Board Geometry/Outline")
		(27 "Margin" user)
		(31 "F.CrtYd" user "Package Geometry/Place Bound Top")
		(29 "B.CrtYd" user "Package Geometry/Place Bound Bottom")
		(35 "F.Fab" user "Ref Des/Assembly Top")
		(33 "B.Fab" user "Ref Des/Assembly Bottom")
	)
	(footprint ""
		(layer "F.Cu")
		(at 297.774106 -255.560068 180)
		(property "Reference" "J15"
			(at -2.2098 -81.984088 0)
			(unlocked yes)
			(layer "F.SilkS")
			(effects
				(font
					(size 0.7874 0.5842)
					(thickness 0.1524)
				)
			)
		)
		(property "Value" ""
			(at 0 0 180)
			(layer "F.Fab")
			(effects
				(font
					(size 1.27 1.27)
				)
			)
		)
		(duplicate_pad_numbers_are_jumpers no)
		(pad "139" smd rect
			(at -2.050034 59.075066 90)
			(size 0.519938 1.4986)
			(layers "F.Cu" "F.Mask" "F.Paste")
			(net "GND")
		)
		(pad "140" smd rect
			(at -2.050034 59.92495 90)
			(size 0.519938 1.4986)
			(layers "F.Cu" "F.Mask" "F.Paste")
			(net "M_B_CPU0_SB_DQ<28>")
		)
		(pad "141" smd rect
			(at -2.050034 60.775088 90)
			(size 0.519938 1.4986)
			(layers "F.Cu" "F.Mask" "F.Paste")
			(net "GND")
		)
		(pad "142" smd rect
			(at -2.050034 61.624972 90)
			(size 0.519938 1.4986)
			(layers "F.Cu" "F.Mask" "F.Paste")
			(net "M_B_CPU0_SB_DQ<29>")
		)
		(pad "143" smd rect
			(at -2.050034 62.47511 90)
			(size 0.519938 1.4986)
			(layers "F.Cu" "F.Mask" "F.Paste")
			(net "GND")
		)
		(pad "144" smd rect
			(at -2.050034 63.324994 90)
			(size 0.519938 1.4986)
			(layers "F.Cu" "F.Mask" "F.Paste")
			(net "Net_2264")
		)
		(pad "145" smd rect
			(at 2.050034 -63.324994 90)
			(size 0.519938 1.4986)
			(layers "F.Cu" "F.Mask" "F.Paste")
			(net "P12V_MEM_CPU0")
		)
		(pad "146" smd rect
			(at 2.050034 -62.47511 90)
			(size 0.519938 1.4986)
			(layers "F.Cu" "F.Mask" "F.Paste")
			(net "P12V_MEM_CPU0")
		)
		(pad "147" smd rect
			(at 2.050034 -61.624972 90)
			(size 0.519938 1.4986)
			(layers "F.Cu" "F.Mask" "F.Paste")
			(net "PWRGD_CHB_CPU0_DIMM")
		)
		(pad "148" smd rect
			(at 2.050034 -60.775088 90)
			(size 0.519938 1.4986)
			(layers "F.Cu" "F.Mask" "F.Paste")
			(net "PD_CHB_CPU0_DIMM_SAA")
		)
		(pad "149" smd rect
			(at 2.050034 -59.92495 90)
			(size 0.519938 1.4986)
			(layers "F.Cu" "F.Mask" "F.Paste")
			(net "Net_2265")
		)
		(pad "150" smd rect
			(at 2.050034 -59.075066 90)
			(size 0.519938 1.4986)
			(layers "F.Cu" "F.Mask" "F.Paste")
			(net "Net_2266")
		)
		(pad "151" smd rect
			(at 2.050034 -58.224928 90)
			(size 0.519938 1.4986)
			(layers "F.Cu" "F.Mask" "F.Paste")
			(net "GND")
		)
		(pad "152" smd rect
			(at 2.050034 -57.375044 90)
			(size 0.519938 1.4986)
			(layers "F.Cu" "F.Mask" "F.Paste")
			(net "M_B_CPU0_SA_DQ<2>")
		)
		(pad "153" smd rect
			(at 2.050034 -56.524906 90)
			(size 0.519938 1.4986)
			(layers "F.Cu" "F.Mask" "F.Paste")
			(net "GND")
		)
		(pad "154" smd rect
			(at 2.050034 -55.675022 90)
			(size 0.519938 1.4986)
			(layers "F.Cu" "F.Mask" "F.Paste")
			(net "M_B_CPU0_SA_DQ<3>")
		)
		(pad "155" smd rect
			(at 2.050034 -54.824884 90)
			(size 0.519938 1.4986)
			(layers "F.Cu" "F.Mask" "F.Paste")
			(net "GND")
		)
		(pad "156" smd rect
			(at 2.050034 -53.975 90)
			(size 0.519938 1.4986)
			(layers "F.Cu" "F.Mask" "F.Paste")
			(net "M_B_CPU0_SA_DQS_DN<5>")
		)
		(pad "157" smd rect
			(at 2.050034 -53.125116 90)
			(size 0.519938 1.4986)
			(layers "F.Cu" "F.Mask" "F.Paste")
			(net "M_B_CPU0_SA_DQS_DP<5>")
		)
		(pad "158" smd rect
			(at 2.050034 -52.274978 90)
			(size 0.519938 1.4986)
			(layers "F.Cu" "F.Mask" "F.Paste")
			(net "GND")
		)
		(pad "159" smd rect
			(at 2.050034 -51.425094 90)
			(size 0.519938 1.4986)
			(layers "F.Cu" "F.Mask" "F.Paste")
			(net "M_B_CPU0_SA_DQ<6>")
		)
		(pad "160" smd rect
			(at 2.050034 -50.574956 90)
			(size 0.519938 1.4986)
			(layers "F.Cu" "F.Mask" "F.Paste")
			(net "GND")
		)
		(pad "161" smd rect
			(at 2.050034 -49.725072 90)
			(size 0.519938 1.4986)
			(layers "F.Cu" "F.Mask" "F.Paste")
			(net "M_B_CPU0_SA_DQ<7>")
		)
		(pad "162" smd rect
			(at 2.050034 -48.874934 90)
			(size 0.519938 1.4986)
			(layers "F.Cu" "F.Mask" "F.Paste")
			(net "GND")
		)
		(pad "163" smd rect
			(at 2.050034 -48.02505 90)
			(size 0.519938 1.4986)
			(layers "F.Cu" "F.Mask" "F.Paste")
			(net "M_B_CPU0_SA_DQ<10>")
		)
		(pad "164" smd rect
			(at 2.050034 -47.174912 90)
			(size 0.519938 1.4986)
			(layers "F.Cu" "F.Mask" "F.Paste")
			(net "GND")
		)
		(pad "165" smd rect
			(at 2.050034 -46.325028 90)
			(size 0.519938 1.4986)
			(layers "F.Cu" "F.Mask" "F.Paste")
			(net "M_B_CPU0_SA_DQ<11>")
		)
		(pad "166" smd rect
			(at 2.050034 -45.47489 90)
			(size 0.519938 1.4986)
			(layers "F.Cu" "F.Mask" "F.Paste")
			(net "GND")
		)
		(pad "167" smd rect
			(at 2.050034 -44.625006 90)
			(size 0.519938 1.4986)
			(layers "F.Cu" "F.Mask" "F.Paste")
			(net "M_B_CPU0_SA_DQS_DN<6>")
		)
		(pad "168" smd rect
			(at 2.050034 -43.775122 90)
			(size 0.519938 1.4986)
			(layers "F.Cu" "F.Mask" "F.Paste")
			(net "M_B_CPU0_SA_DQS_DP<6>")
		)
		(pad "169" smd rect
			(at 2.050034 -42.924984 90)
			(size 0.519938 1.4986)
			(layers "F.Cu" "F.Mask" "F.Paste")
			(net "GND")
		)
		(pad "170" smd rect
			(at 2.050034 -42.0751 90)
			(size 0.519938 1.4986)
			(layers "F.Cu" "F.Mask" "F.Paste")
			(net "M_B_CPU0_SA_DQ<14>")
		)
		(pad "171" smd rect
			(at 2.050034 -41.224962 90)
			(size 0.519938 1.4986)
			(layers "F.Cu" "F.Mask" "F.Paste")
			(net "GND")
		)
		(pad "172" smd rect
			(at 2.050034 -40.375078 90)
			(size 0.519938 1.4986)
			(layers "F.Cu" "F.Mask" "F.Paste")
			(net "M_B_CPU0_SA_DQ<15>")
		)
		(pad "173" smd rect
			(at 2.050034 -39.52494 90)
			(size 0.519938 1.4986)
			(layers "F.Cu" "F.Mask" "F.Paste")
			(net "GND")
		)
		(pad "174" smd rect
			(at 2.050034 -38.675056 90)
			(size 0.519938 1.4986)
			(layers "F.Cu" "F.Mask" "F.Paste")
			(net "M_B_CPU0_SA_DQ<18>")
		)
		(pad "175" smd rect
			(at 2.050034 -37.824918 90)
			(size 0.519938 1.4986)
			(layers "F.Cu" "F.Mask" "F.Paste")
			(net "GND")
		)
		(pad "176" smd rect
			(at 2.050034 -36.975034 90)
			(size 0.519938 1.4986)
			(layers "F.Cu" "F.Mask" "F.Paste")
			(net "M_B_CPU0_SA_DQ<19>")
		)
		(pad "177" smd rect
			(at 2.050034 -36.124896 90)
			(size 0.519938 1.4986)
			(layers "F.Cu" "F.Mask" "F.Paste")
			(net "GND")
		)
		(pad "178" smd rect
			(at 2.050034 -35.275012 90)
			(size 0.519938 1.4986)
			(layers "F.Cu" "F.Mask" "F.Paste")
			(net "M_B_CPU0_SA_DQS_DN<7>")
		)
		(pad "179" smd rect
			(at 2.050034 -34.425128 90)
			(size 0.519938 1.4986)
			(layers "F.Cu" "F.Mask" "F.Paste")
			(net "M_B_CPU0_SA_DQS_DP<7>")
		)
		(pad "180" smd rect
			(at 2.050034 -33.57499 90)
			(size 0.519938 1.4986)
			(layers "F.Cu" "F.Mask" "F.Paste")
			(net "GND")
		)
		(pad "181" smd rect
			(at 2.050034 -32.725106 90)
			(size 0.519938 1.4986)
			(layers "F.Cu" "F.Mask" "F.Paste")
			(net "M_B_CPU0_SA_DQ<22>")
		)
		(pad "182" smd rect
			(at 2.050034 -31.874968 90)
			(size 0.519938 1.4986)
			(layers "F.Cu" "F.Mask" "F.Paste")
			(net "GND")
		)
		(pad "183" smd rect
			(at 2.050034 -31.025084 90)
			(size 0.519938 1.4986)
			(layers "F.Cu" "F.Mask" "F.Paste")
			(net "M_B_CPU0_SA_DQ<23>")
		)
		(pad "184" smd rect
			(at 2.050034 -30.174946 90)
			(size 0.519938 1.4986)
			(layers "F.Cu" "F.Mask" "F.Paste")
			(net "GND")
		)
	)
)
